(kicad_pcb
	(version 20260206)
	(generator "pcbnew")
	(generator_version "10.0")
	(general
		(thickness 1.6)
		(legacy_teardrops no)
	)
	(paper "A4")
	(title_block
		(title "01162023_DA0F0TEBIF0_F0T_Expander_BD_F_brd_V02_OCP.brd")
		(comment 1 "Grand Teton / footprints 8388-8396 of 9728")
	)
	(layers
		(0 "F.Cu" signal "TOP")
		(4 "In1.Cu" signal "GND")
		(6 "In2.Cu" signal "VCC")
		(8 "In3.Cu" signal "VCC1")
		(10 "In4.Cu" signal "GND1")
		(12 "In5.Cu" signal "IN1")
		(14 "In6.Cu" signal "GND2")
		(16 "In7.Cu" signal "IN2")
		(18 "In8.Cu" signal "GND3")
		(20 "In9.Cu" signal "IN3")
		(22 "In10.Cu" signal "GND4")
		(24 "In11.Cu" signal "IN4")
		(26 "In12.Cu" signal "GND5")
		(28 "In13.Cu" signal "IN5")
		(30 "In14.Cu" signal "GND6")
		(32 "In15.Cu" signal "IN6")
		(34 "In16.Cu" signal "GND7")
		(2 "B.Cu" signal "BOTTOM")
		(9 "F.Adhes" user "F.Adhesive")
		(11 "B.Adhes" user "B.Adhesive")
		(13 "F.Paste" user "Package Geometry/Pastemask Top")
		(15 "B.Paste" user "Package Geometry/Pastemask Bottom")
		(5 "F.SilkS" user "Ref Des/Silkscreen Top")
		(7 "B.SilkS" user "Ref Des/Silkscreen Bottom")
		(1 "F.Mask" user "Board Geometry/Soldermask Top")
		(3 "B.Mask" user "Board Geometry/Soldermask Bottom")
		(17 "Dwgs.User" user "User.Drawings")
		(19 "Cmts.User" user "User.Comments")
		(21 "Eco1.User" user "User.Eco1")
		(23 "Eco2.User" user "User.Eco2")
		(25 "Edge.Cuts" user "Board Geometry/Outline")
		(27 "Margin" user)
		(31 "F.CrtYd" user "Package Geometry/Place Bound Top")
		(29 "B.CrtYd" user "Package Geometry/Place Bound Bottom")
		(35 "F.Fab" user "Ref Des/Assembly Top")
		(33 "B.Fab" user "Ref Des/Assembly Bottom")
	)
	(footprint ""
		(layer "B.Cu")
		(at 227.317046 -141.443202 90)
		(property "Reference" "C2805"
			(at 0 0 90)
			(layer "B.SilkS")
			(hide yes)
			(effects
				(font
					(size 1.27 1.27)
				)
				(justify mirror)
			)
		)
		(property "Value" ""
			(at 0 0 90)
			(layer "B.Fab")
			(effects
				(font
					(size 1.27 1.27)
				)
				(justify mirror)
			)
		)
		(duplicate_pad_numbers_are_jumpers no)
		(fp_line
			(start 1.2954 -0.5842)
			(end -1.2954 -0.5842)
			(stroke
				(width 0.1524)
				(type default)
			)
			(layer "B.SilkS")
		)
		(fp_line
			(start -1.2954 -0.5842)
			(end -1.2954 0.5842)
			(stroke
				(width 0.1524)
				(type default)
			)
			(layer "B.SilkS")
		)
		(fp_line
			(start 1.2954 0.5842)
			(end 1.2954 -0.5842)
			(stroke
				(width 0.1524)
				(type default)
			)
			(layer "B.SilkS")
		)
		(fp_line
			(start -1.2954 0.5842)
			(end 1.2954 0.5842)
			(stroke
				(width 0.1524)
				(type default)
			)
			(layer "B.SilkS")
		)
		(fp_line
			(start 0.8636 -0.4572)
			(end -0.8636 -0.4572)
			(stroke
				(width 0.1)
				(type default)
			)
			(layer "B.Fab")
		)
		(fp_line
			(start -0.8636 -0.4572)
			(end -0.8636 -0.4064)
			(stroke
				(width 0.1)
				(type default)
			)
			(layer "B.Fab")
		)
		(fp_line
			(start 1.1938 -0.4064)
			(end 0.8636 -0.4064)
			(stroke
				(width 0.1)
				(type default)
			)
			(layer "B.Fab")
		)
		(fp_line
			(start 0.8636 -0.4064)
			(end 0.8636 -0.4572)
			(stroke
				(width 0.1)
				(type default)
			)
			(layer "B.Fab")
		)
		(fp_line
			(start -0.8636 -0.4064)
			(end -1.1938 -0.4064)
			(stroke
				(width 0.1)
				(type default)
			)
			(layer "B.Fab")
		)
		(fp_line
			(start -1.1938 -0.4064)
			(end -1.1938 0.4064)
			(stroke
				(width 0.1)
				(type default)
			)
			(layer "B.Fab")
		)
		(fp_line
			(start 1.1938 0.4064)
			(end 1.1938 -0.4064)
			(stroke
				(width 0.1)
				(type default)
			)
			(layer "B.Fab")
		)
		(fp_line
			(start 0.8636 0.4064)
			(end 1.1938 0.4064)
			(stroke
				(width 0.1)
				(type default)
			)
			(layer "B.Fab")
		)
		(fp_line
			(start -0.8636 0.4064)
			(end -0.8636 0.4572)
			(stroke
				(width 0.1)
				(type default)
			)
			(layer "B.Fab")
		)
		(fp_line
			(start -1.1938 0.4064)
			(end -0.8636 0.4064)
			(stroke
				(width 0.1)
				(type default)
			)
			(layer "B.Fab")
		)
		(fp_line
			(start 0.8636 0.4572)
			(end 0.8636 0.4064)
			(stroke
				(width 0.1)
				(type default)
			)
			(layer "B.Fab")
		)
		(fp_line
			(start -0.8636 0.4572)
			(end 0.8636 0.4572)
			(stroke
				(width 0.1)
				(type default)
			)
			(layer "B.Fab")
		)
		(pad "1" smd rect
			(at 0.7366 0)
			(size 0.7112 0.8128)
			(layers "B.Cu" "B.Mask" "B.Paste")
			(net "P3V3_CLK_GEN_VDDPT_CK440_PEX")
		)
		(pad "2" smd rect
			(at -0.7366 0)
			(size 0.7112 0.8128)
			(layers "B.Cu" "B.Mask" "B.Paste")
			(net "GND")
		)
	)
	(footprint ""
		(layer "B.Cu")
		(at 304.728626 -249.628406)
		(property "Reference" "C2780"
			(at 0 0 0)
			(layer "B.SilkS")
			(hide yes)
			(effects
				(font
					(size 1.27 1.27)
				)
				(justify mirror)
			)
		)
		(property "Value" ""
			(at 0 0 0)
			(layer "B.Fab")
			(effects
				(font
					(size 1.27 1.27)
				)
				(justify mirror)
			)
		)
		(duplicate_pad_numbers_are_jumpers no)
		(fp_line
			(start -0.7874 -0.4064)
			(end -0.7874 0.4064)
			(stroke
				(width 0.1524)
				(type default)
			)
			(layer "B.SilkS")
		)
		(fp_line
			(start -0.7874 0.4064)
			(end 0.7874 0.4064)
			(stroke
				(width 0.1524)
				(type default)
			)
			(layer "B.SilkS")
		)
		(fp_line
			(start 0.7874 -0.4064)
			(end -0.7874 -0.4064)
			(stroke
				(width 0.1524)
				(type default)
			)
			(layer "B.SilkS")
		)
		(fp_line
			(start 0.7874 0.4064)
			(end 0.7874 -0.4064)
			(stroke
				(width 0.1524)
				(type default)
			)
			(layer "B.SilkS")
		)
		(fp_line
			(start -0.67945 -0.3048)
			(end -0.67945 0.3048)
			(stroke
				(width 0.1)
				(type default)
			)
			(layer "B.Fab")
		)
		(fp_line
			(start -0.67945 0.3048)
			(end -0.120396 0.3048)
			(stroke
				(width 0.1)
				(type default)
			)
			(layer "B.Fab")
		)
		(fp_line
			(start -0.12065 -0.3048)
			(end -0.67945 -0.3048)
			(stroke
				(width 0.1)
				(type default)
			)
			(layer "B.Fab")
		)
		(fp_line
			(start -0.12065 -0.2794)
			(end -0.12065 -0.3048)
			(stroke
				(width 0.1)
				(type default)
			)
			(layer "B.Fab")
		)
		(fp_line
			(start -0.120396 0.2794)
			(end 0.12065 0.2794)
			(stroke
				(width 0.1)
				(type default)
			)
			(layer "B.Fab")
		)
		(fp_line
			(start -0.120396 0.3048)
			(end -0.120396 0.2794)
			(stroke
				(width 0.1)
				(type default)
			)
			(layer "B.Fab")
		)
		(fp_line
			(start 0.12065 -0.305054)
			(end 0.12065 -0.2794)
			(stroke
				(width 0.1)
				(type default)
			)
			(layer "B.Fab")
		)
		(fp_line
			(start 0.12065 -0.2794)
			(end -0.12065 -0.2794)
			(stroke
				(width 0.1)
				(type default)
			)
			(layer "B.Fab")
		)
		(fp_line
			(start 0.12065 0.2794)
			(end 0.12065 0.3048)
			(stroke
				(width 0.1)
				(type default)
			)
			(layer "B.Fab")
		)
		(fp_line
			(start 0.12065 0.3048)
			(end 0.67945 0.3048)
			(stroke
				(width 0.1)
				(type default)
			)
			(layer "B.Fab")
		)
		(fp_line
			(start 0.67945 -0.305054)
			(end 0.12065 -0.305054)
			(stroke
				(width 0.1)
				(type default)
			)
			(layer "B.Fab")
		)
		(fp_line
			(start 0.67945 0.3048)
			(end 0.67945 -0.305054)
			(stroke
				(width 0.1)
				(type default)
			)
			(layer "B.Fab")
		)
		(pad "1" smd circle
			(at 0.40005 0 180)
			(size 0 0)
			(layers "B.Cu" "B.Mask" "B.Paste")
			(net "GND")
		)
		(pad "2" smd circle
			(at -0.40005 0 180)
			(size 0 0)
			(layers "B.Cu" "B.Mask" "B.Paste")
			(net "P3V3_AUX")
		)
	)
	(footprint ""
		(layer "B.Cu")
		(at 291.84981 -303.499774 -90)
		(property "Reference" "C3251"
			(at 0 0 90)
			(layer "B.SilkS")
			(hide yes)
			(effects
				(font
					(size 1.27 1.27)
				)
				(justify mirror)
			)
		)
		(property "Value" ""
			(at 0 0 90)
			(layer "B.Fab")
			(effects
				(font
					(size 1.27 1.27)
				)
				(justify mirror)
			)
		)
		(duplicate_pad_numbers_are_jumpers no)
		(fp_line
			(start -0.299974 0.150114)
			(end 0.299974 0.150114)
			(stroke
				(width 0.1)
				(type default)
			)
			(layer "B.Fab")
		)
		(fp_line
			(start 0.299974 0.150114)
			(end 0.299974 -0.150114)
			(stroke
				(width 0.1)
				(type default)
			)
			(layer "B.Fab")
		)
		(fp_line
			(start -0.299974 -0.150114)
			(end -0.299974 0.150114)
			(stroke
				(width 0.1)
				(type default)
			)
			(layer "B.Fab")
		)
		(fp_line
			(start 0.299974 -0.150114)
			(end -0.299974 -0.150114)
			(stroke
				(width 0.1)
				(type default)
			)
			(layer "B.Fab")
		)
		(pad "1" smd rect
			(at 0.2667 0 90)
			(size 0.3048 0.381)
			(layers "B.Cu" "B.Mask" "B.Paste")
			(net "P1V25_PEX2")
		)
		(pad "2" smd rect
			(at -0.2667 0 90)
			(size 0.3048 0.381)
			(layers "B.Cu" "B.Mask" "B.Paste")
			(net "GND")
		)
	)
	(footprint ""
		(layer "B.Cu")
		(at 284.249876 -299.699934 -90)
		(property "Reference" "C1691"
			(at 0 0 90)
			(layer "B.SilkS")
			(hide yes)
			(effects
				(font
					(size 1.27 1.27)
				)
				(justify mirror)
			)
		)
		(property "Value" ""
			(at 0 0 90)
			(layer "B.Fab")
			(effects
				(font
					(size 1.27 1.27)
				)
				(justify mirror)
			)
		)
		(duplicate_pad_numbers_are_jumpers no)
		(fp_line
			(start -0.299974 0.150114)
			(end 0.299974 0.150114)
			(stroke
				(width 0.1)
				(type default)
			)
			(layer "B.Fab")
		)
		(fp_line
			(start 0.299974 0.150114)
			(end 0.299974 -0.150114)
			(stroke
				(width 0.1)
				(type default)
			)
			(layer "B.Fab")
		)
		(fp_line
			(start -0.299974 -0.150114)
			(end -0.299974 0.150114)
			(stroke
				(width 0.1)
				(type default)
			)
			(layer "B.Fab")
		)
		(fp_line
			(start 0.299974 -0.150114)
			(end -0.299974 -0.150114)
			(stroke
				(width 0.1)
				(type default)
			)
			(layer "B.Fab")
		)
		(pad "1" smd rect
			(at 0.2667 0 90)
			(size 0.3048 0.381)
			(layers "B.Cu" "B.Mask" "B.Paste")
			(net "P0V8_SERDES_VDDA_PEX2")
		)
		(pad "2" smd rect
			(at -0.2667 0 90)
			(size 0.3048 0.381)
			(layers "B.Cu" "B.Mask" "B.Paste")
			(net "GND")
		)
	)
	(footprint ""
		(layer "B.Cu")
		(at 126.634748 -293.506906 90)
		(property "Reference" "PC103"
			(at 0 0 90)
			(layer "B.SilkS")
			(hide yes)
			(effects
				(font
					(size 1.27 1.27)
				)
				(justify mirror)
			)
		)
		(property "Value" ""
			(at 0 0 90)
			(layer "B.Fab")
			(effects
				(font
					(size 1.27 1.27)
				)
				(justify mirror)
			)
		)
		(duplicate_pad_numbers_are_jumpers no)
		(fp_line
			(start 1.524 -0.762)
			(end -1.524 -0.762)
			(stroke
				(width 0.1524)
				(type default)
			)
			(layer "B.SilkS")
		)
		(fp_line
			(start -1.524 -0.762)
			(end -1.524 0.762)
			(stroke
				(width 0.1524)
				(type default)
			)
			(layer "B.SilkS")
		)
		(fp_line
			(start 1.524 0.762)
			(end 1.524 -0.762)
			(stroke
				(width 0.1524)
				(type default)
			)
			(layer "B.SilkS")
		)
		(fp_line
			(start -1.524 0.762)
			(end 1.524 0.762)
			(stroke
				(width 0.1524)
				(type default)
			)
			(layer "B.SilkS")
		)
		(fp_line
			(start 1.1049 -0.724916)
			(end 1.1049 0.724916)
			(stroke
				(width 0.1)
				(type default)
			)
			(layer "B.Fab")
		)
		(fp_line
			(start -1.1049 -0.724916)
			(end 1.1049 -0.724916)
			(stroke
				(width 0.1)
				(type default)
			)
			(layer "B.Fab")
		)
		(fp_line
			(start 1.1049 0.724916)
			(end -1.1049 0.724916)
			(stroke
				(width 0.1)
				(type default)
			)
			(layer "B.Fab")
		)
		(fp_line
			(start -1.1049 0.724916)
			(end -1.1049 -0.724916)
			(stroke
				(width 0.1)
				(type default)
			)
			(layer "B.Fab")
		)
		(pad "1" smd rect
			(at 0.889 0 90)
			(size 1.016 1.27)
			(layers "B.Cu" "B.Mask" "B.Paste")
			(net "P0V8_PEX1")
		)
		(pad "2" smd rect
			(at -0.889 0 90)
			(size 1.016 1.27)
			(layers "B.Cu" "B.Mask" "B.Paste")
			(net "GND")
		)
	)
	(footprint ""
		(layer "B.Cu")
		(at 395.03604 -291.624766)
		(property "Reference" "C3581"
			(at 0 0 0)
			(layer "B.SilkS")
			(hide yes)
			(effects
				(font
					(size 1.27 1.27)
				)
				(justify mirror)
			)
		)
		(property "Value" ""
			(at 0 0 0)
			(layer "B.Fab")
			(effects
				(font
					(size 1.27 1.27)
				)
				(justify mirror)
			)
		)
		(duplicate_pad_numbers_are_jumpers no)
		(fp_line
			(start -0.299974 -0.150114)
			(end -0.299974 0.150114)
			(stroke
				(width 0.1)
				(type default)
			)
			(layer "B.Fab")
		)
		(fp_line
			(start -0.299974 0.150114)
			(end 0.299974 0.150114)
			(stroke
				(width 0.1)
				(type default)
			)
			(layer "B.Fab")
		)
		(fp_line
			(start 0.299974 -0.150114)
			(end -0.299974 -0.150114)
			(stroke
				(width 0.1)
				(type default)
			)
			(layer "B.Fab")
		)
		(fp_line
			(start 0.299974 0.150114)
			(end 0.299974 -0.150114)
			(stroke
				(width 0.1)
				(type default)
			)
			(layer "B.Fab")
		)
		(pad "1" smd rect
			(at 0.2667 0 180)
			(size 0.3048 0.381)
			(layers "B.Cu" "B.Mask" "B.Paste")
			(net "PCEPLL7_VDDA18_PEX3")
		)
		(pad "2" smd rect
			(at -0.2667 0 180)
			(size 0.3048 0.381)
			(layers "B.Cu" "B.Mask" "B.Paste")
			(net "GND")
		)
	)
	(footprint ""
		(layer "B.Cu")
		(at 415.549842 -303.499774 -90)
		(property "Reference" "C3455"
			(at 0 0 90)
			(layer "B.SilkS")
			(hide yes)
			(effects
				(font
					(size 1.27 1.27)
				)
				(justify mirror)
			)
		)
		(property "Value" ""
			(at 0 0 90)
			(layer "B.Fab")
			(effects
				(font
					(size 1.27 1.27)
				)
				(justify mirror)
			)
		)
		(duplicate_pad_numbers_are_jumpers no)
		(fp_line
			(start -0.299974 0.150114)
			(end 0.299974 0.150114)
			(stroke
				(width 0.1)
				(type default)
			)
			(layer "B.Fab")
		)
		(fp_line
			(start 0.299974 0.150114)
			(end 0.299974 -0.150114)
			(stroke
				(width 0.1)
				(type default)
			)
			(layer "B.Fab")
		)
		(fp_line
			(start -0.299974 -0.150114)
			(end -0.299974 0.150114)
			(stroke
				(width 0.1)
				(type default)
			)
			(layer "B.Fab")
		)
		(fp_line
			(start 0.299974 -0.150114)
			(end -0.299974 -0.150114)
			(stroke
				(width 0.1)
				(type default)
			)
			(layer "B.Fab")
		)
		(pad "1" smd rect
			(at 0.2667 0 90)
			(size 0.3048 0.381)
			(layers "B.Cu" "B.Mask" "B.Paste")
			(net "P1V25_PEX3")
		)
		(pad "2" smd rect
			(at -0.2667 0 90)
			(size 0.3048 0.381)
			(layers "B.Cu" "B.Mask" "B.Paste")
			(net "GND")
		)
	)
	(footprint ""
		(layer "B.Cu")
		(at 212.09 -203.327 90)
		(property "Reference" "R1521"
			(at 0 0 90)
			(layer "B.SilkS")
			(hide yes)
			(effects
				(font
					(size 1.27 1.27)
				)
				(justify mirror)
			)
		)
		(property "Value" ""
			(at 0 0 90)
			(layer "B.Fab")
			(effects
				(font
					(size 1.27 1.27)
				)
				(justify mirror)
			)
		)
		(duplicate_pad_numbers_are_jumpers no)
		(fp_line
			(start 0.7874 -0.4064)
			(end -0.7874 -0.4064)
			(stroke
				(width 0.1524)
				(type default)
			)
			(layer "B.SilkS")
		)
		(fp_line
			(start -0.7874 -0.4064)
			(end -0.7874 0.4064)
			(stroke
				(width 0.1524)
				(type default)
			)
			(layer "B.SilkS")
		)
		(fp_line
			(start 0.7874 0.4064)
			(end 0.7874 -0.4064)
			(stroke
				(width 0.1524)
				(type default)
			)
			(layer "B.SilkS")
		)
		(fp_line
			(start -0.7874 0.4064)
			(end 0.7874 0.4064)
			(stroke
				(width 0.1524)
				(type default)
			)
			(layer "B.SilkS")
		)
		(fp_line
			(start 0.67945 -0.305054)
			(end 0.12065 -0.305054)
			(stroke
				(width 0.1)
				(type default)
			)
			(layer "B.Fab")
		)
		(fp_line
			(start 0.12065 -0.305054)
			(end 0.12065 -0.2794)
			(stroke
				(width 0.1)
				(type default)
			)
			(layer "B.Fab")
		)
		(fp_line
			(start -0.12065 -0.3048)
			(end -0.67945 -0.3048)
			(stroke
				(width 0.1)
				(type default)
			)
			(layer "B.Fab")
		)
		(fp_line
			(start -0.67945 -0.3048)
			(end -0.67945 0.3048)
			(stroke
				(width 0.1)
				(type default)
			)
			(layer "B.Fab")
		)
		(fp_line
			(start 0.12065 -0.2794)
			(end -0.12065 -0.2794)
			(stroke
				(width 0.1)
				(type default)
			)
			(layer "B.Fab")
		)
		(fp_line
			(start -0.12065 -0.2794)
			(end -0.12065 -0.3048)
			(stroke
				(width 0.1)
				(type default)
			)
			(layer "B.Fab")
		)
		(fp_line
			(start 0.12065 0.2794)
			(end 0.12065 0.3048)
			(stroke
				(width 0.1)
				(type default)
			)
			(layer "B.Fab")
		)
		(fp_line
			(start -0.120396 0.2794)
			(end 0.12065 0.2794)
			(stroke
				(width 0.1)
				(type default)
			)
			(layer "B.Fab")
		)
		(fp_line
			(start 0.67945 0.3048)
			(end 0.67945 -0.305054)
			(stroke
				(width 0.1)
				(type default)
			)
			(layer "B.Fab")
		)
		(fp_line
			(start 0.12065 0.3048)
			(end 0.67945 0.3048)
			(stroke
				(width 0.1)
				(type default)
			)
			(layer "B.Fab")
		)
		(fp_line
			(start -0.120396 0.3048)
			(end -0.120396 0.2794)
			(stroke
				(width 0.1)
				(type default)
			)
			(layer "B.Fab")
		)
		(fp_line
			(start -0.67945 0.3048)
			(end -0.120396 0.3048)
			(stroke
				(width 0.1)
				(type default)
			)
			(layer "B.Fab")
		)
		(pad "1" smd circle
			(at 0.40005 0 270)
			(size 0 0)
			(layers "B.Cu" "B.Mask" "B.Paste")
			(net "SMB_NIC5_LS_R_SDA")
		)
		(pad "2" smd circle
			(at -0.40005 0 270)
			(size 0 0)
			(layers "B.Cu" "B.Mask" "B.Paste")
			(net "SMB_NIC5_R_SDA")
		)
	)
	(footprint ""
		(layer "B.Cu")
		(at 49.5554 -153.0096)
		(property "Reference" "R19"
			(at 0 0 0)
			(layer "B.SilkS")
			(hide yes)
			(effects
				(font
					(size 1.27 1.27)
				)
				(justify mirror)
			)
		)
		(property "Value" ""
			(at 0 0 0)
			(layer "B.Fab")
			(effects
				(font
					(size 1.27 1.27)
				)
				(justify mirror)
			)
		)
		(duplicate_pad_numbers_are_jumpers no)
		(fp_line
			(start -0.7874 -0.4064)
			(end -0.7874 0.4064)
			(stroke
				(width 0.1524)
				(type default)
			)
			(layer "B.SilkS")
		)
		(fp_line
			(start -0.7874 0.4064)
			(end 0.7874 0.4064)
			(stroke
				(width 0.1524)
				(type default)
			)
			(layer "B.SilkS")
		)
		(fp_line
			(start 0.7874 -0.4064)
			(end -0.7874 -0.4064)
			(stroke
				(width 0.1524)
				(type default)
			)
			(layer "B.SilkS")
		)
		(fp_line
			(start 0.7874 0.4064)
			(end 0.7874 -0.4064)
			(stroke
				(width 0.1524)
				(type default)
			)
			(layer "B.SilkS")
		)
		(fp_line
			(start -0.67945 -0.3048)
			(end -0.67945 0.3048)
			(stroke
				(width 0.1)
				(type default)
			)
			(layer "B.Fab")
		)
		(fp_line
			(start -0.67945 0.3048)
			(end -0.120396 0.3048)
			(stroke
				(width 0.1)
				(type default)
			)
			(layer "B.Fab")
		)
		(fp_line
			(start -0.12065 -0.3048)
			(end -0.67945 -0.3048)
			(stroke
				(width 0.1)
				(type default)
			)
			(layer "B.Fab")
		)
		(fp_line
			(start -0.12065 -0.2794)
			(end -0.12065 -0.3048)
			(stroke
				(width 0.1)
				(type default)
			)
			(layer "B.Fab")
		)
		(fp_line
			(start -0.120396 0.2794)
			(end 0.12065 0.2794)
			(stroke
				(width 0.1)
				(type default)
			)
			(layer "B.Fab")
		)
		(fp_line
			(start -0.120396 0.3048)
			(end -0.120396 0.2794)
			(stroke
				(width 0.1)
				(type default)
			)
			(layer "B.Fab")
		)
		(fp_line
			(start 0.12065 -0.305054)
			(end 0.12065 -0.2794)
			(stroke
				(width 0.1)
				(type default)
			)
			(layer "B.Fab")
		)
		(fp_line
			(start 0.12065 -0.2794)
			(end -0.12065 -0.2794)
			(stroke
				(width 0.1)
				(type default)
			)
			(layer "B.Fab")
		)
		(fp_line
			(start 0.12065 0.2794)
			(end 0.12065 0.3048)
			(stroke
				(width 0.1)
				(type default)
			)
			(layer "B.Fab")
		)
		(fp_line
			(start 0.12065 0.3048)
			(end 0.67945 0.3048)
			(stroke
				(width 0.1)
				(type default)
			)
			(layer "B.Fab")
		)
		(fp_line
			(start 0.67945 -0.305054)
			(end 0.12065 -0.305054)
			(stroke
				(width 0.1)
				(type default)
			)
			(layer "B.Fab")
		)
		(fp_line
			(start 0.67945 0.3048)
			(end 0.67945 -0.305054)
			(stroke
				(width 0.1)
				(type default)
			)
			(layer "B.Fab")
		)
		(pad "1" smd circle
			(at 0.40005 0 180)
			(size 0 0)
			(layers "B.Cu" "B.Mask" "B.Paste")
			(net "NCSI_NIC0_TXD1")
		)
		(pad "2" smd circle
			(at -0.40005 0 180)
			(size 0 0)
			(layers "B.Cu" "B.Mask" "B.Paste")
			(net "GND")
		)
	)
)
